(kicad_pcb
	(version 20221018)
	(generator pcbnew)
	(general
    (thickness 1.62)
  )
	(paper "A4")
	(title_block
    (title "ECP5 - Datacenter Secure Control Module (DC-SCM)")
    (date "2024-07-01")
    (rev "1.2.1")
		(comment 9 "footprints 7-15 of 506")
	)
	(layers
    (0 "F.Cu" signal)
    (1 "In1.Cu" power)
    (2 "In2.Cu" signal)
    (3 "In3.Cu" power)
    (4 "In4.Cu" power)
    (5 "In5.Cu" signal)
    (6 "In6.Cu" power)
    (31 "B.Cu" signal)
    (32 "B.Adhes" user "B.Adhesive")
    (33 "F.Adhes" user "F.Adhesive")
    (34 "B.Paste" user)
    (35 "F.Paste" user)
    (36 "B.SilkS" user "B.Silkscreen")
    (37 "F.SilkS" user "F.Silkscreen")
    (38 "B.Mask" user)
    (39 "F.Mask" user)
    (40 "Dwgs.User" user "User.Drawings")
    (41 "Cmts.User" user "User.Comments")
    (42 "Eco1.User" user "User.Eco1")
    (43 "Eco2.User" user "User.Eco2")
    (44 "Edge.Cuts" user)
    (45 "Margin" user)
    (46 "B.CrtYd" user "B.Courtyard")
    (47 "F.CrtYd" user "F.Courtyard")
    (48 "B.Fab" user)
    (49 "F.Fab" user)
  )
	(footprint "antmicro-footprints:C_0402_1005Metric" (layer "F.Cu")
    (at 72.384 124.67 90)
    (descr "Capacitor SMD 0402")
    (tags "capacitor SMD 0402")
    (property "Author" "Antmicro")
    (property "Dielectric" "X5R")
    (property "License" "Apache-2.0")
    (property "MPN" "GRM155R61H104KE14D")
    (property "Manufacturer" "Murata")
    (property "Public" "False")
    (property "Sheetfile" "ddr3.kicad_sch")
    (property "Sheetname" "DDR3")
    (property "Val" "100n")
    (property "Voltage" "50V")
    (property "ki_description" "SMD Multilayer Ceramic Capacitor, 0.1 µF, 50 V, 0402 [1005 Metric], ± 10%, X5R, GRM Series")
    (property "ki_keywords" "0402, SMT, CAPACITOR, PASSIVE, CERAMIC, MLCC")
    (attr smd)
    (fp_text reference "C240" (at -3.755 -0.004 90) (layer "F.SilkS")
        (effects (font (size 0.7 0.7) (thickness 0.127)))
    )
    (fp_text value "C_100n_0402" (at 0 1.17 90) (layer "F.Fab")
        (effects (font (size 1 1) (thickness 0.15)))
    )
    (fp_text user "License: Apache-2.0" (at -0.939 5.799 90) (layer "F.Fab") hide
        (effects (font (size 0.7 0.7) (thickness 0.15)) (justify left bottom))
    )
    (fp_text user "Author: Antmicro" (at -0.939 3.399 90) (layer "F.Fab") hide
        (effects (font (size 0.7 0.7) (thickness 0.15)) (justify left bottom))
    )
    (fp_text user "${REFERENCE}" (at 0 0 90) (layer "F.Fab")
        (effects (font (size 0.25 0.25) (thickness 0.04)))
    )
    (fp_rect (start -0.925 -0.47) (end 0.925 0.47)
      (stroke (width 0.05) (type default)) (fill none) (layer "F.CrtYd"))
    (fp_line (start -0.494 -0.25) (end 0.504 -0.25)
      (stroke (width 0.15) (type solid)) (layer "F.Fab"))
    (fp_line (start -0.494 0.248) (end -0.494 -0.25)
      (stroke (width 0.15) (type solid)) (layer "F.Fab"))
    (fp_line (start 0.504 -0.25) (end 0.504 0.248)
      (stroke (width 0.15) (type solid)) (layer "F.Fab"))
    (fp_line (start 0.504 0.248) (end -0.494 0.248)
      (stroke (width 0.15) (type solid)) (layer "F.Fab"))
    (pad "1" smd roundrect (at -0.48 0 90) (size 0.59 0.64) (layers "F.Cu" "F.Paste" "F.Mask") (roundrect_rratio 0.25)
      (net 1 "GND") (pintype "passive"))
    (pad "2" smd roundrect (at 0.48 0 90) (size 0.59 0.64) (layers "F.Cu" "F.Paste" "F.Mask") (roundrect_rratio 0.25)
      (net 3 "VCC1V35") (pintype "passive"))
  )
	(footprint "antmicro-footprints:C_0402_1005Metric" (layer "F.Cu")
    (at 75.32 117.92 180)
    (descr "Capacitor SMD 0402")
    (tags "capacitor SMD 0402")
    (property "Author" "Antmicro")
    (property "Dielectric" "X5R")
    (property "License" "Apache-2.0")
    (property "MPN" "GRM155R61H104KE14D")
    (property "Manufacturer" "Murata")
    (property "Public" "False")
    (property "Sheetfile" "ddr3.kicad_sch")
    (property "Sheetname" "DDR3")
    (property "Val" "100n")
    (property "Voltage" "50V")
    (property "ki_description" "SMD Multilayer Ceramic Capacitor, 0.1 µF, 50 V, 0402 [1005 Metric], ± 10%, X5R, GRM Series")
    (property "ki_keywords" "0402, SMT, CAPACITOR, PASSIVE, CERAMIC, MLCC")
    (attr smd)
    (fp_text reference "C201" (at -2.2 -0.035 180) (layer "F.SilkS")
        (effects (font (size 0.7 0.7) (thickness 0.127)))
    )
    (fp_text value "C_100n_0402" (at 0 1.17) (layer "F.Fab")
        (effects (font (size 1 1) (thickness 0.15)))
    )
    (fp_text user "${REFERENCE}" (at 0 0) (layer "F.Fab")
        (effects (font (size 0.25 0.25) (thickness 0.04)))
    )
    (fp_text user "License: Apache-2.0" (at -0.939 5.799 180) (layer "F.Fab") hide
        (effects (font (size 0.7 0.7) (thickness 0.15)) (justify left bottom))
    )
    (fp_text user "Author: Antmicro" (at -0.939 3.399 180) (layer "F.Fab") hide
        (effects (font (size 0.7 0.7) (thickness 0.15)) (justify left bottom))
    )
    (fp_rect (start -0.925 -0.47) (end 0.925 0.47)
      (stroke (width 0.05) (type default)) (fill none) (layer "F.CrtYd"))
    (fp_line (start -0.494 -0.25) (end 0.504 -0.25)
      (stroke (width 0.15) (type solid)) (layer "F.Fab"))
    (fp_line (start -0.494 0.248) (end -0.494 -0.25)
      (stroke (width 0.15) (type solid)) (layer "F.Fab"))
    (fp_line (start 0.504 -0.25) (end 0.504 0.248)
      (stroke (width 0.15) (type solid)) (layer "F.Fab"))
    (fp_line (start 0.504 0.248) (end -0.494 0.248)
      (stroke (width 0.15) (type solid)) (layer "F.Fab"))
    (pad "1" smd roundrect (at -0.48 0 180) (size 0.59 0.64) (layers "F.Cu" "F.Paste" "F.Mask") (roundrect_rratio 0.25)
      (net 1 "GND") (pintype "passive"))
    (pad "2" smd roundrect (at 0.48 0 180) (size 0.59 0.64) (layers "F.Cu" "F.Paste" "F.Mask") (roundrect_rratio 0.25)
      (net 217 "DDR3_VREF") (pintype "passive"))
  )
	(footprint "antmicro-footprints:C_0402_1005Metric" (layer "F.Cu")
    (at 74.352 124.67 90)
    (descr "Capacitor SMD 0402")
    (tags "capacitor SMD 0402")
    (property "Author" "Antmicro")
    (property "Dielectric" "")
    (property "License" "Apache-2.0")
    (property "MPN" "CC0402MRX5R5BB106")
    (property "Manufacturer" "YAGEO")
    (property "Public" "False")
    (property "Sheetfile" "ddr3.kicad_sch")
    (property "Sheetname" "DDR3")
    (property "Val" "10u")
    (property "Voltage" "")
    (property "ki_description" "SMD Multilayer Ceramic Capacitor, 10 µF, 6.3 V, 0402 [1005 Metric], ± 20%, X5R, CC Series")
    (property "ki_keywords" "0402, SMT, CAPACITOR, PASSIVE, MLCC, CERAMIC")
    (attr smd)
    (fp_text reference "C199" (at -3.735 0.058 90) (layer "F.SilkS")
        (effects (font (size 0.7 0.7) (thickness 0.127)))
    )
    (fp_text value "C_10u_0402" (at 0 1.17 90) (layer "F.Fab")
        (effects (font (size 1 1) (thickness 0.15)))
    )
    (fp_text user "Author: Antmicro" (at -0.939 3.399 90) (layer "F.Fab") hide
        (effects (font (size 0.7 0.7) (thickness 0.15)) (justify left bottom))
    )
    (fp_text user "License: Apache-2.0" (at -0.939 5.799 90) (layer "F.Fab") hide
        (effects (font (size 0.7 0.7) (thickness 0.15)) (justify left bottom))
    )
    (fp_text user "${REFERENCE}" (at 0 0 90) (layer "F.Fab")
        (effects (font (size 0.25 0.25) (thickness 0.04)))
    )
    (fp_rect (start -0.925 -0.47) (end 0.925 0.47)
      (stroke (width 0.05) (type default)) (fill none) (layer "F.CrtYd"))
    (fp_line (start -0.494 -0.25) (end 0.504 -0.25)
      (stroke (width 0.15) (type solid)) (layer "F.Fab"))
    (fp_line (start -0.494 0.248) (end -0.494 -0.25)
      (stroke (width 0.15) (type solid)) (layer "F.Fab"))
    (fp_line (start 0.504 -0.25) (end 0.504 0.248)
      (stroke (width 0.15) (type solid)) (layer "F.Fab"))
    (fp_line (start 0.504 0.248) (end -0.494 0.248)
      (stroke (width 0.15) (type solid)) (layer "F.Fab"))
    (pad "1" smd roundrect (at -0.48 0 90) (size 0.59 0.64) (layers "F.Cu" "F.Paste" "F.Mask") (roundrect_rratio 0.25)
      (net 1 "GND") (pintype "passive"))
    (pad "2" smd roundrect (at 0.48 0 90) (size 0.59 0.64) (layers "F.Cu" "F.Paste" "F.Mask") (roundrect_rratio 0.25)
      (net 166 "/DDR3/DDR3_VTT") (pintype "passive"))
  )
	(footprint "antmicro-footprints:R_0402_1005Metric" (layer "F.Cu")
    (at 71.9 118.07)
    (descr "Resistor SMD 0402")
    (tags "resistor SMD 0402")
    (property "Author" "Antmicro")
    (property "License" "Apache-2.0")
    (property "MPN" "CR0402-FX-1002GLF")
    (property "Manufacturer" "Bourns")
    (property "Public" "False")
    (property "Sheetfile" "ddr3.kicad_sch")
    (property "Sheetname" "DDR3")
    (property "Tolerance" "1%")
    (property "Val" "10k")
    (property "ki_description" "SMD Chip Resistor, 10 kohm, ± 1%, 62.5 mW, 0402 [1005 Metric], Thick Film, General Purpose")
    (property "ki_keywords" "0402, SMT, RESISTOR, PASSIVE")
    (attr smd)
    (fp_text reference "R80" (at -1.89 -0.085) (layer "F.SilkS")
        (effects (font (size 0.7 0.7) (thickness 0.127)))
    )
    (fp_text value "R_10k_0402" (at 0 1.17) (layer "F.Fab")
        (effects (font (size 1 1) (thickness 0.15)))
    )
    (fp_text user "License: Apache-2.0" (at -0.95 5.169) (layer "F.Fab") hide
        (effects (font (size 0.7 0.7) (thickness 0.15)) (justify left bottom))
    )
    (fp_text user "${REFERENCE}" (at 0 0) (layer "F.Fab")
        (effects (font (size 0.25 0.25) (thickness 0.04)))
    )
    (fp_text user "Author: Antmicro" (at -0.95 4.169) (layer "F.Fab") hide
        (effects (font (size 0.7 0.7) (thickness 0.15)) (justify left bottom))
    )
    (fp_rect (start -0.925 -0.47) (end 0.925 0.47)
      (stroke (width 0.05) (type default)) (fill none) (layer "F.CrtYd"))
    (fp_rect (start -0.5 -0.25) (end 0.5 0.25)
      (stroke (width 0.15) (type solid)) (fill none) (layer "F.Fab"))
    (pad "1" smd roundrect (at -0.48 0) (size 0.59 0.64) (layers "F.Cu" "F.Paste" "F.Mask") (roundrect_rratio 0.25)
      (net 2 "VCC3V3") (pintype "passive"))
    (pad "2" smd roundrect (at 0.48 0) (size 0.59 0.64) (layers "F.Cu" "F.Paste" "F.Mask") (roundrect_rratio 0.25)
      (net 408 "Net-(U11-PGOOD)") (pintype "passive"))
  )
	(footprint "antmicro-footprints:R_0402_1005Metric" (layer "F.Cu")
    (at 70.42 122.04 90)
    (descr "Resistor SMD 0402")
    (tags "resistor SMD 0402")
    (property "Author" "Antmicro")
    (property "License" "Apache-2.0")
    (property "MPN" "CR0402-FX-1002GLF")
    (property "Manufacturer" "Bourns")
    (property "Public" "False")
    (property "Sheetfile" "ddr3.kicad_sch")
    (property "Sheetname" "DDR3")
    (property "Tolerance" "1%")
    (property "Val" "10k")
    (property "ki_description" "SMD Chip Resistor, 10 kohm, ± 1%, 62.5 mW, 0402 [1005 Metric], Thick Film, General Purpose")
    (property "ki_keywords" "0402, SMT, RESISTOR, PASSIVE")
    (attr smd)
    (fp_text reference "R78" (at 0.03 -2.16 90) (layer "F.SilkS")
        (effects (font (size 0.7 0.7) (thickness 0.127)))
    )
    (fp_text value "R_10k_0402" (at 0 1.17 90) (layer "F.Fab")
        (effects (font (size 1 1) (thickness 0.15)))
    )
    (fp_text user "License: Apache-2.0" (at -0.95 5.169 90) (layer "F.Fab") hide
        (effects (font (size 0.7 0.7) (thickness 0.15)) (justify left bottom))
    )
    (fp_text user "Author: Antmicro" (at -0.95 4.169 90) (layer "F.Fab") hide
        (effects (font (size 0.7 0.7) (thickness 0.15)) (justify left bottom))
    )
    (fp_text user "${REFERENCE}" (at 0 0 90) (layer "F.Fab")
        (effects (font (size 0.25 0.25) (thickness 0.04)))
    )
    (fp_rect (start -0.925 -0.47) (end 0.925 0.47)
      (stroke (width 0.05) (type default)) (fill none) (layer "F.CrtYd"))
    (fp_rect (start -0.5 -0.25) (end 0.5 0.25)
      (stroke (width 0.15) (type solid)) (fill none) (layer "F.Fab"))
    (pad "1" smd roundrect (at -0.48 0 90) (size 0.59 0.64) (layers "F.Cu" "F.Paste" "F.Mask") (roundrect_rratio 0.25)
      (net 305 "Net-(U11-REFIN)") (pintype "passive"))
    (pad "2" smd roundrect (at 0.48 0 90) (size 0.59 0.64) (layers "F.Cu" "F.Paste" "F.Mask") (roundrect_rratio 0.25)
      (net 1 "GND") (pintype "passive"))
  )
	(footprint "antmicro-footprints:C_0402_1005Metric" (layer "F.Cu")
    (at 76.32 124.67 90)
    (descr "Capacitor SMD 0402")
    (tags "capacitor SMD 0402")
    (property "Author" "Antmicro")
    (property "Dielectric" "")
    (property "License" "Apache-2.0")
    (property "MPN" "CC0402MRX5R5BB106")
    (property "Manufacturer" "YAGEO")
    (property "Public" "False")
    (property "Sheetfile" "ddr3.kicad_sch")
    (property "Sheetname" "DDR3")
    (property "Val" "10u")
    (property "Voltage" "")
    (property "ki_description" "SMD Multilayer Ceramic Capacitor, 10 µF, 6.3 V, 0402 [1005 Metric], ± 20%, X5R, CC Series")
    (property "ki_keywords" "0402, SMT, CAPACITOR, PASSIVE, MLCC, CERAMIC")
    (attr smd)
    (fp_text reference "C197" (at -3.765 0.02 270) (layer "F.SilkS")
        (effects (font (size 0.7 0.7) (thickness 0.127)))
    )
    (fp_text value "C_10u_0402" (at 0 1.17 90) (layer "F.Fab")
        (effects (font (size 1 1) (thickness 0.15)))
    )
    (fp_text user "License: Apache-2.0" (at -0.939 5.799 90) (layer "F.Fab") hide
        (effects (font (size 0.7 0.7) (thickness 0.15)) (justify left bottom))
    )
    (fp_text user "${REFERENCE}" (at 0 0 90) (layer "F.Fab")
        (effects (font (size 0.25 0.25) (thickness 0.04)))
    )
    (fp_text user "Author: Antmicro" (at -0.939 3.399 90) (layer "F.Fab") hide
        (effects (font (size 0.7 0.7) (thickness 0.15)) (justify left bottom))
    )
    (fp_rect (start -0.925 -0.47) (end 0.925 0.47)
      (stroke (width 0.05) (type default)) (fill none) (layer "F.CrtYd"))
    (fp_line (start -0.494 -0.25) (end 0.504 -0.25)
      (stroke (width 0.15) (type solid)) (layer "F.Fab"))
    (fp_line (start -0.494 0.248) (end -0.494 -0.25)
      (stroke (width 0.15) (type solid)) (layer "F.Fab"))
    (fp_line (start 0.504 -0.25) (end 0.504 0.248)
      (stroke (width 0.15) (type solid)) (layer "F.Fab"))
    (fp_line (start 0.504 0.248) (end -0.494 0.248)
      (stroke (width 0.15) (type solid)) (layer "F.Fab"))
    (pad "1" smd roundrect (at -0.48 0 90) (size 0.59 0.64) (layers "F.Cu" "F.Paste" "F.Mask") (roundrect_rratio 0.25)
      (net 1 "GND") (pintype "passive"))
    (pad "2" smd roundrect (at 0.48 0 90) (size 0.59 0.64) (layers "F.Cu" "F.Paste" "F.Mask") (roundrect_rratio 0.25)
      (net 166 "/DDR3/DDR3_VTT") (pintype "passive"))
  )
	(footprint "antmicro-footprints:C_0402_1005Metric" (layer "F.Cu")
    (at 73.368 124.67 90)
    (descr "Capacitor SMD 0402")
    (tags "capacitor SMD 0402")
    (property "Author" "Antmicro")
    (property "Dielectric" "X5R")
    (property "License" "Apache-2.0")
    (property "MPN" "GRM155R61H104KE14D")
    (property "Manufacturer" "Murata")
    (property "Public" "False")
    (property "Sheetfile" "ddr3.kicad_sch")
    (property "Sheetname" "DDR3")
    (property "Val" "100n")
    (property "Voltage" "50V")
    (property "ki_description" "SMD Multilayer Ceramic Capacitor, 0.1 µF, 50 V, 0402 [1005 Metric], ± 10%, X5R, GRM Series")
    (property "ki_keywords" "0402, SMT, CAPACITOR, PASSIVE, CERAMIC, MLCC")
    (attr smd)
    (fp_text reference "C202" (at -3.745 0.032 90) (layer "F.SilkS")
        (effects (font (size 0.7 0.7) (thickness 0.127)))
    )
    (fp_text value "C_100n_0402" (at 0 1.17 90) (layer "F.Fab")
        (effects (font (size 1 1) (thickness 0.15)))
    )
    (fp_text user "Author: Antmicro" (at -0.939 3.399 90) (layer "F.Fab") hide
        (effects (font (size 0.7 0.7) (thickness 0.15)) (justify left bottom))
    )
    (fp_text user "${REFERENCE}" (at 0 0 90) (layer "F.Fab")
        (effects (font (size 0.25 0.25) (thickness 0.04)))
    )
    (fp_text user "License: Apache-2.0" (at -0.939 5.799 90) (layer "F.Fab") hide
        (effects (font (size 0.7 0.7) (thickness 0.15)) (justify left bottom))
    )
    (fp_rect (start -0.925 -0.47) (end 0.925 0.47)
      (stroke (width 0.05) (type default)) (fill none) (layer "F.CrtYd"))
    (fp_line (start -0.494 -0.25) (end 0.504 -0.25)
      (stroke (width 0.15) (type solid)) (layer "F.Fab"))
    (fp_line (start -0.494 0.248) (end -0.494 -0.25)
      (stroke (width 0.15) (type solid)) (layer "F.Fab"))
    (fp_line (start 0.504 -0.25) (end 0.504 0.248)
      (stroke (width 0.15) (type solid)) (layer "F.Fab"))
    (fp_line (start 0.504 0.248) (end -0.494 0.248)
      (stroke (width 0.15) (type solid)) (layer "F.Fab"))
    (pad "1" smd roundrect (at -0.48 0 90) (size 0.59 0.64) (layers "F.Cu" "F.Paste" "F.Mask") (roundrect_rratio 0.25)
      (net 1 "GND") (pintype "passive"))
    (pad "2" smd roundrect (at 0.48 0 90) (size 0.59 0.64) (layers "F.Cu" "F.Paste" "F.Mask") (roundrect_rratio 0.25)
      (net 3 "VCC1V35") (pintype "passive"))
  )
	(footprint "antmicro-footprints:C_0402_1005Metric" (layer "F.Cu")
    (at 75.336 124.67 90)
    (descr "Capacitor SMD 0402")
    (tags "capacitor SMD 0402")
    (property "Author" "Antmicro")
    (property "Dielectric" "")
    (property "License" "Apache-2.0")
    (property "MPN" "CC0402MRX5R5BB106")
    (property "Manufacturer" "YAGEO")
    (property "Public" "False")
    (property "Sheetfile" "ddr3.kicad_sch")
    (property "Sheetname" "DDR3")
    (property "Val" "10u")
    (property "Voltage" "")
    (property "ki_description" "SMD Multilayer Ceramic Capacitor, 10 µF, 6.3 V, 0402 [1005 Metric], ± 20%, X5R, CC Series")
    (property "ki_keywords" "0402, SMT, CAPACITOR, PASSIVE, MLCC, CERAMIC")
    (attr smd)
    (fp_text reference "C198" (at -3.745 0.004 90) (layer "F.SilkS")
        (effects (font (size 0.7 0.7) (thickness 0.127)))
    )
    (fp_text value "C_10u_0402" (at 0 1.17 90) (layer "F.Fab")
        (effects (font (size 1 1) (thickness 0.15)))
    )
    (fp_text user "License: Apache-2.0" (at -0.939 5.799 90) (layer "F.Fab") hide
        (effects (font (size 0.7 0.7) (thickness 0.15)) (justify left bottom))
    )
    (fp_text user "${REFERENCE}" (at 0 0 90) (layer "F.Fab")
        (effects (font (size 0.25 0.25) (thickness 0.04)))
    )
    (fp_text user "Author: Antmicro" (at -0.939 3.399 90) (layer "F.Fab") hide
        (effects (font (size 0.7 0.7) (thickness 0.15)) (justify left bottom))
    )
    (fp_rect (start -0.925 -0.47) (end 0.925 0.47)
      (stroke (width 0.05) (type default)) (fill none) (layer "F.CrtYd"))
    (fp_line (start -0.494 -0.25) (end 0.504 -0.25)
      (stroke (width 0.15) (type solid)) (layer "F.Fab"))
    (fp_line (start -0.494 0.248) (end -0.494 -0.25)
      (stroke (width 0.15) (type solid)) (layer "F.Fab"))
    (fp_line (start 0.504 -0.25) (end 0.504 0.248)
      (stroke (width 0.15) (type solid)) (layer "F.Fab"))
    (fp_line (start 0.504 0.248) (end -0.494 0.248)
      (stroke (width 0.15) (type solid)) (layer "F.Fab"))
    (pad "1" smd roundrect (at -0.48 0 90) (size 0.59 0.64) (layers "F.Cu" "F.Paste" "F.Mask") (roundrect_rratio 0.25)
      (net 1 "GND") (pintype "passive"))
    (pad "2" smd roundrect (at 0.48 0 90) (size 0.59 0.64) (layers "F.Cu" "F.Paste" "F.Mask") (roundrect_rratio 0.25)
      (net 166 "/DDR3/DDR3_VTT") (pintype "passive"))
  )
	(footprint "antmicro-footprints:C_0402_1005Metric" (layer "F.Cu")
    (at 75.32 116.92 180)
    (descr "Capacitor SMD 0402")
    (tags "capacitor SMD 0402")
    (property "Author" "Antmicro")
    (property "Dielectric" "X5R")
    (property "License" "Apache-2.0")
    (property "MPN" "GRM155R61H104KE14D")
    (property "Manufacturer" "Murata")
    (property "Public" "False")
    (property "Sheetfile" "ddr3.kicad_sch")
    (property "Sheetname" "DDR3")
    (property "Val" "100n")
    (property "Voltage" "50V")
    (property "ki_description" "SMD Multilayer Ceramic Capacitor, 0.1 µF, 50 V, 0402 [1005 Metric], ± 10%, X5R, GRM Series")
    (property "ki_keywords" "0402, SMT, CAPACITOR, PASSIVE, CERAMIC, MLCC")
    (attr smd)
    (fp_text reference "C200" (at 2.27 0.05) (layer "F.SilkS")
        (effects (font (size 0.7 0.7) (thickness 0.127)))
    )
    (fp_text value "C_100n_0402" (at 0 1.17) (layer "F.Fab")
        (effects (font (size 1 1) (thickness 0.15)))
    )
    (fp_text user "Author: Antmicro" (at -0.939 3.399 180) (layer "F.Fab") hide
        (effects (font (size 0.7 0.7) (thickness 0.15)) (justify left bottom))
    )
    (fp_text user "License: Apache-2.0" (at -0.939 5.799 180) (layer "F.Fab") hide
        (effects (font (size 0.7 0.7) (thickness 0.15)) (justify left bottom))
    )
    (fp_text user "${REFERENCE}" (at 0 0) (layer "F.Fab")
        (effects (font (size 0.25 0.25) (thickness 0.04)))
    )
    (fp_rect (start -0.925 -0.47) (end 0.925 0.47)
      (stroke (width 0.05) (type default)) (fill none) (layer "F.CrtYd"))
    (fp_line (start -0.494 -0.25) (end 0.504 -0.25)
      (stroke (width 0.15) (type solid)) (layer "F.Fab"))
    (fp_line (start -0.494 0.248) (end -0.494 -0.25)
      (stroke (width 0.15) (type solid)) (layer "F.Fab"))
    (fp_line (start 0.504 -0.25) (end 0.504 0.248)
      (stroke (width 0.15) (type solid)) (layer "F.Fab"))
    (fp_line (start 0.504 0.248) (end -0.494 0.248)
      (stroke (width 0.15) (type solid)) (layer "F.Fab"))
    (pad "1" smd roundrect (at -0.48 0 180) (size 0.59 0.64) (layers "F.Cu" "F.Paste" "F.Mask") (roundrect_rratio 0.25)
      (net 1 "GND") (pintype "passive"))
    (pad "2" smd roundrect (at 0.48 0 180) (size 0.59 0.64) (layers "F.Cu" "F.Paste" "F.Mask") (roundrect_rratio 0.25)
      (net 217 "DDR3_VREF") (pintype "passive"))
  )
)
